(kicad_pcb
	(version 20260206)
	(generator "pcbnew")
	(generator_version "10.0")
	(general
		(thickness 1.6)
		(legacy_teardrops no)
	)
	(paper "A4")
	(title_block
		(title "Wiwynn_Tioga_Pass_MB.brd")
		(comment 1 "Tioga Pass / footprints 1241-1247 of 4770")
	)
	(layers
		(0 "F.Cu" signal "TOP")
		(4 "In1.Cu" signal "L2GND")
		(6 "In2.Cu" signal "L3")
		(8 "In3.Cu" signal "L4GND")
		(10 "In4.Cu" signal "L5")
		(12 "In5.Cu" signal "L6GND")
		(14 "In6.Cu" signal "L7VCC")
		(16 "In7.Cu" signal "L8VCC")
		(18 "In8.Cu" signal "L9GND")
		(20 "In9.Cu" signal "L10")
		(22 "In10.Cu" signal "L11GND")
		(24 "In11.Cu" signal "L12")
		(26 "In12.Cu" signal "L13GND")
		(2 "B.Cu" signal "BOTTOM")
		(9 "F.Adhes" user "F.Adhesive")
		(11 "B.Adhes" user "B.Adhesive")
		(13 "F.Paste" user "Package Geometry/Pastemask Top")
		(15 "B.Paste" user "Package Geometry/Pastemask Bottom")
		(5 "F.SilkS" user "Ref Des/Silkscreen Top")
		(7 "B.SilkS" user "Ref Des/Silkscreen Bottom")
		(1 "F.Mask" user "Board Geometry/Soldermask Top")
		(3 "B.Mask" user "Board Geometry/Soldermask Bottom")
		(17 "Dwgs.User" user "User.Drawings")
		(19 "Cmts.User" user "User.Comments")
		(21 "Eco1.User" user "User.Eco1")
		(23 "Eco2.User" user "User.Eco2")
		(25 "Edge.Cuts" user "Board Geometry/Outline")
		(27 "Margin" user)
		(31 "F.CrtYd" user "Package Geometry/Place Bound Top")
		(29 "B.CrtYd" user "Package Geometry/Place Bound Bottom")
		(35 "F.Fab" user "Ref Des/Assembly Top")
		(33 "B.Fab" user "Ref Des/Assembly Bottom")
	)
	(footprint ""
		(layer "F.Cu")
		(at 451.3326 -22.4282)
		(property "Reference" "R9W31"
			(at 0 0 0)
			(layer "F.SilkS")
			(hide yes)
			(effects
				(font
					(size 1.27 1.27)
				)
			)
		)
		(property "Value" "*"
			(at 0.064008 -4.108196 0)
			(unlocked yes)
			(layer "F.Fab")
			(hide yes)
			(effects
				(font
					(size 1.27 1.016)
					(thickness 0.1524)
				)
			)
		)
		(property "Device Type" "21K5R2F-GP_RCL_GP-21K5R2F-GP,6A"
			(at 0.064008 -5.632196 0)
			(unlocked yes)
			(layer "F.Fab")
			(hide yes)
			(effects
				(font
					(size 1.27 1.016)
					(thickness 0.1524)
				)
			)
		)
		(duplicate_pad_numbers_are_jumpers no)
		(fp_line
			(start -0.508 -0.9398)
			(end -0.508 0.9398)
			(stroke
				(width 0.1524)
				(type default)
			)
			(layer "F.SilkS")
		)
		(fp_line
			(start 0.508 -0.9398)
			(end -0.508 -0.9398)
			(stroke
				(width 0.1524)
				(type default)
			)
			(layer "F.SilkS")
		)
		(fp_rect
			(start -0.508 0.9398)
			(end 0.508 -0.9398)
			(stroke
				(width 0)
				(type default)
			)
			(fill no)
			(layer "F.CrtYd")
		)
		(fp_rect
			(start -0.508 0.9398)
			(end 0.508 -0.9398)
			(stroke
				(width 0)
				(type default)
			)
			(fill no)
			(layer "F.Fab")
		)
		(pad "1" smd custom
			(at 0 -0.4445)
			(size 0.1397 0.1397)
			(layers "F.Cu" "F.Mask" "F.Paste")
			(net "P2V5_AUX_BMC")
			(options
				(clearance outline)
				(anchor circle)
			)
			(primitives
				(gr_poly
					(pts
						(arc
							(start -0.1778 -0.2794)
							(mid -0.249642 -0.249642)
							(end -0.2794 -0.1778)
						)
						(arc
							(start -0.2794 0.1778)
							(mid -0.249642 0.249642)
							(end -0.1778 0.2794)
						)
						(arc
							(start 0.1778 0.2794)
							(mid 0.249642 0.249642)
							(end 0.2794 0.1778)
						)
						(arc
							(start 0.2794 -0.1778)
							(mid 0.249642 -0.249642)
							(end 0.1778 -0.2794)
						)
					)
					(width 0)
					(fill yes)
				)
			)
		)
		(pad "2" smd custom
			(at 0 0.4445)
			(size 0.1397 0.1397)
			(layers "F.Cu" "F.Mask" "F.Paste")
			(net "VR_P2V5_BMC_STBY_FB")
			(options
				(clearance outline)
				(anchor circle)
			)
			(primitives
				(gr_poly
					(pts
						(arc
							(start -0.1778 -0.2794)
							(mid -0.249642 -0.249642)
							(end -0.2794 -0.1778)
						)
						(arc
							(start -0.2794 0.1778)
							(mid -0.249642 0.249642)
							(end -0.1778 0.2794)
						)
						(arc
							(start 0.1778 0.2794)
							(mid 0.249642 0.249642)
							(end 0.2794 0.1778)
						)
						(arc
							(start 0.2794 -0.1778)
							(mid 0.249642 -0.249642)
							(end 0.1778 -0.2794)
						)
					)
					(width 0)
					(fill yes)
				)
			)
		)
	)
	(footprint ""
		(layer "F.Cu")
		(at 363.165644 -10.916158)
		(property "Reference" "C7G6"
			(at 0 0 0)
			(layer "F.SilkS")
			(hide yes)
			(effects
				(font
					(size 1.27 1.27)
				)
			)
		)
		(property "Value" ""
			(at 0 0 0)
			(layer "F.Fab")
			(effects
				(font
					(size 1.27 1.27)
				)
			)
		)
		(duplicate_pad_numbers_are_jumpers no)
		(fp_rect
			(start -0.3048 0.9906)
			(end 0.3048 -0.1016)
			(stroke
				(width 0)
				(type default)
			)
			(fill no)
			(layer "F.CrtYd")
		)
		(fp_line
			(start -0.3048 -0.1016)
			(end -0.3048 0.9906)
			(stroke
				(width 0.1)
				(type default)
			)
			(layer "F.Fab")
		)
		(fp_line
			(start -0.3048 0.9906)
			(end 0.3048 0.9906)
			(stroke
				(width 0.1)
				(type default)
			)
			(layer "F.Fab")
		)
		(fp_line
			(start 0.3048 -0.1016)
			(end -0.3048 -0.1016)
			(stroke
				(width 0.1)
				(type default)
			)
			(layer "F.Fab")
		)
		(fp_line
			(start 0.3048 0.9906)
			(end 0.3048 -0.1016)
			(stroke
				(width 0.1)
				(type default)
			)
			(layer "F.Fab")
		)
		(pad "1" smd rect
			(at 0 0)
			(size 0.508 0.508)
			(layers "F.Cu" "F.Mask" "F.Paste")
			(net "P3E_CPU0_PE2_SS_TXN<15>")
		)
		(pad "2" smd rect
			(at 0 0.889)
			(size 0.508 0.508)
			(layers "F.Cu" "F.Mask" "F.Paste")
			(net "P3E_CPU0_PE2_SS_C_TXN<15>")
		)
		(zone
			(layer "F.Cu")
			(hatch none 0.5)
			(connect_pads
				(clearance 0)
			)
			(min_thickness 0.25)
			(keepout
				(tracks not_allowed)
				(vias allowed)
				(pads allowed)
				(copperpour not_allowed)
				(footprints allowed)
			)
			(placement
				(enabled no)
				(sheetname "")
			)
			(fill
				(thermal_gap 0.5)
				(thermal_bridge_width 0.5)
				(island_removal_mode 0)
			)
			(polygon
				(pts
					(xy 362.911644 -10.281158) (xy 363.419644 -10.281158) (xy 363.419644 -10.662158) (xy 362.911644 -10.662158)
				)
			)
		)
		(zone
			(layer "F.Cu")
			(hatch none 0.5)
			(connect_pads
				(clearance 0)
			)
			(min_thickness 0.25)
			(keepout
				(tracks allowed)
				(vias not_allowed)
				(pads allowed)
				(copperpour not_allowed)
				(footprints allowed)
			)
			(placement
				(enabled no)
				(sheetname "")
			)
			(fill
				(thermal_gap 0.5)
				(thermal_bridge_width 0.5)
				(island_removal_mode 0)
			)
			(polygon
				(pts
					(xy 362.911644 -10.281158) (xy 363.419644 -10.281158) (xy 363.419644 -10.662158) (xy 362.911644 -10.662158)
				)
			)
		)
	)
	(footprint ""
		(layer "F.Cu")
		(at 407.8605 -114.554 90)
		(property "Reference" "R2M7"
			(at 0 0 90)
			(layer "F.SilkS")
			(hide yes)
			(effects
				(font
					(size 1.27 1.27)
				)
			)
		)
		(property "Value" ""
			(at 0 0 90)
			(layer "F.Fab")
			(effects
				(font
					(size 1.27 1.27)
				)
			)
		)
		(duplicate_pad_numbers_are_jumpers no)
		(fp_poly
			(pts
				(xy -0.2794 -0.1016) (xy 0.2794 -0.1016) (xy 0.2794 0.9906) (xy -0.2794 0.9906)
			)
			(stroke
				(width 0)
				(type default)
			)
			(fill no)
			(layer "F.CrtYd")
		)
		(fp_line
			(start 0.2794 -0.1016)
			(end -0.2794 -0.1016)
			(stroke
				(width 0.1)
				(type default)
			)
			(layer "F.Fab")
		)
		(fp_line
			(start -0.2794 -0.1016)
			(end -0.2794 0.9906)
			(stroke
				(width 0.1)
				(type default)
			)
			(layer "F.Fab")
		)
		(fp_line
			(start 0.2794 0.9906)
			(end 0.2794 -0.1016)
			(stroke
				(width 0.1)
				(type default)
			)
			(layer "F.Fab")
		)
		(fp_line
			(start -0.2794 0.9906)
			(end 0.2794 0.9906)
			(stroke
				(width 0.1)
				(type default)
			)
			(layer "F.Fab")
		)
		(pad "1" smd rect
			(at 0 0 90)
			(size 0.508 0.508)
			(layers "F.Cu" "F.Mask" "F.Paste")
			(net "FM_ADR_MODE_SEL_R")
		)
		(pad "2" smd rect
			(at 0 0.889 90)
			(size 0.508 0.508)
			(layers "F.Cu" "F.Mask" "F.Paste")
			(net "FM_ADR_MODE_SEL")
		)
		(zone
			(layer "F.Cu")
			(hatch none 0.5)
			(connect_pads
				(clearance 0)
			)
			(min_thickness 0.25)
			(keepout
				(tracks allowed)
				(vias not_allowed)
				(pads allowed)
				(copperpour not_allowed)
				(footprints allowed)
			)
			(placement
				(enabled no)
				(sheetname "")
			)
			(fill
				(thermal_gap 0.5)
				(thermal_bridge_width 0.5)
				(island_removal_mode 0)
			)
			(polygon
				(pts
					(xy 408.1145 -114.3) (xy 408.1145 -114.808) (xy 408.4955 -114.808) (xy 408.4955 -114.3)
				)
			)
		)
		(zone
			(layer "F.Cu")
			(hatch none 0.5)
			(connect_pads
				(clearance 0)
			)
			(min_thickness 0.25)
			(keepout
				(tracks not_allowed)
				(vias allowed)
				(pads allowed)
				(copperpour not_allowed)
				(footprints allowed)
			)
			(placement
				(enabled no)
				(sheetname "")
			)
			(fill
				(thermal_gap 0.5)
				(thermal_bridge_width 0.5)
				(island_removal_mode 0)
			)
			(polygon
				(pts
					(xy 408.4955 -114.3) (xy 408.4955 -114.808) (xy 408.1145 -114.808) (xy 408.1145 -114.3)
				)
			)
		)
	)
	(footprint ""
		(layer "F.Cu")
		(at 111.5314 -83.8962)
		(property "Reference" "R3D3"
			(at 0 0 0)
			(layer "F.SilkS")
			(hide yes)
			(effects
				(font
					(size 1.27 1.27)
				)
			)
		)
		(property "Value" ""
			(at 0 0 0)
			(layer "F.Fab")
			(effects
				(font
					(size 1.27 1.27)
				)
			)
		)
		(duplicate_pad_numbers_are_jumpers no)
		(fp_poly
			(pts
				(xy -0.2794 -0.1016) (xy 0.2794 -0.1016) (xy 0.2794 0.9906) (xy -0.2794 0.9906)
			)
			(stroke
				(width 0)
				(type default)
			)
			(fill no)
			(layer "F.CrtYd")
		)
		(fp_line
			(start -0.2794 -0.1016)
			(end -0.2794 0.9906)
			(stroke
				(width 0.1)
				(type default)
			)
			(layer "F.Fab")
		)
		(fp_line
			(start -0.2794 0.9906)
			(end 0.2794 0.9906)
			(stroke
				(width 0.1)
				(type default)
			)
			(layer "F.Fab")
		)
		(fp_line
			(start 0.2794 -0.1016)
			(end -0.2794 -0.1016)
			(stroke
				(width 0.1)
				(type default)
			)
			(layer "F.Fab")
		)
		(fp_line
			(start 0.2794 0.9906)
			(end 0.2794 -0.1016)
			(stroke
				(width 0.1)
				(type default)
			)
			(layer "F.Fab")
		)
		(pad "1" smd rect
			(at 0 0)
			(size 0.508 0.508)
			(layers "F.Cu" "F.Mask" "F.Paste")
			(net "A_CPU1_KLM_RCOMP2")
		)
		(pad "2" smd rect
			(at 0 0.889)
			(size 0.508 0.508)
			(layers "F.Cu" "F.Mask" "F.Paste")
			(net "GND")
		)
		(zone
			(layer "F.Cu")
			(hatch none 0.5)
			(connect_pads
				(clearance 0)
			)
			(min_thickness 0.25)
			(keepout
				(tracks allowed)
				(vias not_allowed)
				(pads allowed)
				(copperpour not_allowed)
				(footprints allowed)
			)
			(placement
				(enabled no)
				(sheetname "")
			)
			(fill
				(thermal_gap 0.5)
				(thermal_bridge_width 0.5)
				(island_removal_mode 0)
			)
			(polygon
				(pts
					(xy 111.2774 -83.6422) (xy 111.7854 -83.6422) (xy 111.7854 -83.2612) (xy 111.2774 -83.2612)
				)
			)
		)
		(zone
			(layer "F.Cu")
			(hatch none 0.5)
			(connect_pads
				(clearance 0)
			)
			(min_thickness 0.25)
			(keepout
				(tracks not_allowed)
				(vias allowed)
				(pads allowed)
				(copperpour not_allowed)
				(footprints allowed)
			)
			(placement
				(enabled no)
				(sheetname "")
			)
			(fill
				(thermal_gap 0.5)
				(thermal_bridge_width 0.5)
				(island_removal_mode 0)
			)
			(polygon
				(pts
					(xy 111.2774 -83.2612) (xy 111.7854 -83.2612) (xy 111.7854 -83.6422) (xy 111.2774 -83.6422)
				)
			)
		)
	)
	(footprint ""
		(layer "F.Cu")
		(at 420.624 -109.07014)
		(property "Reference" "U1W2"
			(at 0 0 0)
			(layer "F.SilkS")
			(hide yes)
			(effects
				(font
					(size 1.27 1.27)
				)
			)
		)
		(property "Value" "*"
			(at -0.1143 -9.3091 0)
			(unlocked yes)
			(layer "F.Fab")
			(hide yes)
			(effects
				(font
					(size 1.27 1.016)
					(thickness 0.1524)
				)
			)
		)
		(property "Device Type" "TCA9517DGKR-GP_DISCRET-G8-TCA9A"
			(at -0.1143 -10.9093 0)
			(unlocked yes)
			(layer "F.Fab")
			(hide yes)
			(effects
				(font
					(size 1.27 1.016)
					(thickness 0.1524)
				)
			)
		)
		(duplicate_pad_numbers_are_jumpers no)
		(fp_line
			(start -1.9558 -1.016)
			(end -1.9558 1.016)
			(stroke
				(width 0.1524)
				(type default)
			)
			(layer "F.SilkS")
		)
		(fp_line
			(start -1.9558 -0.5461)
			(end -1.4478 -0.0381)
			(stroke
				(width 0.1524)
				(type default)
			)
			(layer "F.SilkS")
		)
		(fp_line
			(start -1.9558 1.016)
			(end 1.0795 1.016)
			(stroke
				(width 0.1524)
				(type default)
			)
			(layer "F.SilkS")
		)
		(fp_line
			(start -1.778 1.0922)
			(end -1.778 3.048)
			(stroke
				(width 0.508)
				(type default)
			)
			(layer "F.SilkS")
		)
		(fp_line
			(start -1.4478 -0.0381)
			(end -1.9558 0.4699)
			(stroke
				(width 0.1524)
				(type default)
			)
			(layer "F.SilkS")
		)
		(fp_line
			(start 1.0795 -1.016)
			(end -1.9558 -1.016)
			(stroke
				(width 0.1524)
				(type default)
			)
			(layer "F.SilkS")
		)
		(fp_line
			(start 1.0795 1.016)
			(end 1.0795 -1.016)
			(stroke
				(width 0.1524)
				(type default)
			)
			(layer "F.SilkS")
		)
		(fp_poly
			(pts
				(xy -1.1557 -1.016) (xy -1.1557 1.016) (xy 1.1557 1.016) (xy 1.1557 -1.016)
			)
			(stroke
				(width 0)
				(type default)
			)
			(fill yes)
			(layer "F.SilkS")
		)
		(fp_rect
			(start -1.4986 2.4511)
			(end 1.4986 -2.4511)
			(stroke
				(width 0)
				(type default)
			)
			(fill no)
			(layer "F.CrtYd")
		)
		(fp_poly
			(pts
				(xy -2.032 3.302) (xy -2.032 -3.302) (xy 2.032 -3.302) (xy 2.032 -2.1209) (xy 1.4986 -2.1209) (xy 1.4986 -2.4511)
				(xy -1.4986 -2.4511) (xy -1.4986 2.4511) (xy 1.4986 2.4511) (xy 1.4986 -2.1082) (xy 2.032 -2.1082)
				(xy 2.032 3.302)
			)
			(stroke
				(width 0)
				(type default)
			)
			(fill no)
			(layer "F.CrtYd")
		)
		(fp_rect
			(start -2.032 3.302)
			(end 2.032 -3.302)
			(stroke
				(width 0)
				(type default)
			)
			(fill no)
			(layer "F.Fab")
		)
		(pad "1" smd rect
			(at -0.97536 2.05486)
			(size 0.3556 1.524)
			(layers "F.Cu" "F.Mask" "F.Paste")
			(net "PVCCIO_CPU0")
		)
		(pad "2" smd rect
			(at -0.32512 2.05486)
			(size 0.3556 1.524)
			(layers "F.Cu" "F.Mask" "F.Paste")
			(net "SMB_CPU0_PE_HP_GTL_R_SCL")
		)
		(pad "3" smd rect
			(at 0.32512 2.05486)
			(size 0.3556 1.524)
			(layers "F.Cu" "F.Mask" "F.Paste")
			(net "SMB_CPU0_PE_HP_GTL_R_SDA")
		)
		(pad "4" smd rect
			(at 0.97536 2.05486)
			(size 0.3556 1.524)
			(layers "F.Cu" "F.Mask" "F.Paste")
			(net "GND")
		)
		(pad "5" smd rect
			(at 0.97536 -2.05486)
			(size 0.3556 1.524)
			(layers "F.Cu" "F.Mask" "F.Paste")
			(net "TP_SMB_PEHPCPU0_EN")
		)
		(pad "6" smd rect
			(at 0.32512 -2.05486)
			(size 0.3556 1.524)
			(layers "F.Cu" "F.Mask" "F.Paste")
			(net "SMB_PEHPCPU0_STBY_LVC3_R_SDA")
		)
		(pad "7" smd rect
			(at -0.32512 -2.05486)
			(size 0.3556 1.524)
			(layers "F.Cu" "F.Mask" "F.Paste")
			(net "SMB_PEHPCPU0_STBY_LVC3_R_SCL")
		)
		(pad "8" smd rect
			(at -0.97536 -2.05486)
			(size 0.3556 1.524)
			(layers "F.Cu" "F.Mask" "F.Paste")
			(net "P3V3_STBY")
		)
	)
	(footprint ""
		(layer "F.Cu")
		(at 274.43303 -84.796122)
		(property "Reference" "C5D5"
			(at 0 0 0)
			(layer "F.SilkS")
			(hide yes)
			(effects
				(font
					(size 1.27 1.27)
				)
			)
		)
		(property "Value" ""
			(at 0 0 0)
			(layer "F.Fab")
			(effects
				(font
					(size 1.27 1.27)
				)
			)
		)
		(duplicate_pad_numbers_are_jumpers no)
		(fp_poly
			(pts
				(xy -0.4953 -0.2032) (xy 0.4953 -0.2032) (xy 0.4953 1.6002) (xy -0.4953 1.6002)
			)
			(stroke
				(width 0)
				(type default)
			)
			(fill no)
			(layer "F.CrtYd")
		)
		(fp_line
			(start -0.4953 -0.2032)
			(end 0.4953 -0.2032)
			(stroke
				(width 0.1)
				(type default)
			)
			(layer "F.Fab")
		)
		(fp_line
			(start -0.4953 1.6002)
			(end -0.4953 -0.2032)
			(stroke
				(width 0.1)
				(type default)
			)
			(layer "F.Fab")
		)
		(fp_line
			(start 0.4953 -0.2032)
			(end 0.4953 1.6002)
			(stroke
				(width 0.1)
				(type default)
			)
			(layer "F.Fab")
		)
		(fp_line
			(start 0.4953 1.6002)
			(end -0.4953 1.6002)
			(stroke
				(width 0.1)
				(type default)
			)
			(layer "F.Fab")
		)
		(pad "1" smd rect
			(at 0 0)
			(size 0.762 0.889)
			(layers "F.Cu" "F.Mask" "F.Paste")
			(net "PVCCIN_CPU0")
		)
		(pad "2" smd rect
			(at 0 1.397)
			(size 0.762 0.889)
			(layers "F.Cu" "F.Mask" "F.Paste")
			(net "GND")
		)
		(zone
			(layer "F.Cu")
			(hatch none 0.5)
			(connect_pads
				(clearance 0)
			)
			(min_thickness 0.25)
			(keepout
				(tracks not_allowed)
				(vias allowed)
				(pads allowed)
				(copperpour not_allowed)
				(footprints allowed)
			)
			(placement
				(enabled no)
				(sheetname "")
			)
			(fill
				(thermal_gap 0.5)
				(thermal_bridge_width 0.5)
				(island_removal_mode 0)
			)
			(polygon
				(pts
					(xy 274.05203 -84.351622) (xy 274.81403 -84.351622) (xy 274.81403 -83.843622) (xy 274.05203 -83.843622)
				)
			)
		)
	)
	(footprint ""
		(layer "F.Cu")
		(at 170.0276 -131.8768)
		(property "Reference" "R4B3"
			(at 0 0 0)
			(layer "F.SilkS")
			(hide yes)
			(effects
				(font
					(size 1.27 1.27)
				)
			)
		)
		(property "Value" ""
			(at 0 0 0)
			(layer "F.Fab")
			(effects
				(font
					(size 1.27 1.27)
				)
			)
		)
		(duplicate_pad_numbers_are_jumpers no)
		(fp_poly
			(pts
				(xy -0.2794 -0.1016) (xy 0.2794 -0.1016) (xy 0.2794 0.9906) (xy -0.2794 0.9906)
			)
			(stroke
				(width 0)
				(type default)
			)
			(fill no)
			(layer "F.CrtYd")
		)
		(fp_line
			(start -0.2794 -0.1016)
			(end -0.2794 0.9906)
			(stroke
				(width 0.1)
				(type default)
			)
			(layer "F.Fab")
		)
		(fp_line
			(start -0.2794 0.9906)
			(end 0.2794 0.9906)
			(stroke
				(width 0.1)
				(type default)
			)
			(layer "F.Fab")
		)
		(fp_line
			(start 0.2794 -0.1016)
			(end -0.2794 -0.1016)
			(stroke
				(width 0.1)
				(type default)
			)
			(layer "F.Fab")
		)
		(fp_line
			(start 0.2794 0.9906)
			(end 0.2794 -0.1016)
			(stroke
				(width 0.1)
				(type default)
			)
			(layer "F.Fab")
		)
		(pad "1" smd rect
			(at 0 0)
			(size 0.508 0.508)
			(layers "F.Cu" "F.Mask" "F.Paste")
			(net "PVPP_KLM")
		)
		(pad "2" smd rect
			(at 0 0.889)
			(size 0.508 0.508)
			(layers "F.Cu" "F.Mask" "F.Paste")
			(net "VSENSE_PVPP_KLM")
		)
		(zone
			(layer "F.Cu")
			(hatch none 0.5)
			(connect_pads
				(clearance 0)
			)
			(min_thickness 0.25)
			(keepout
				(tracks allowed)
				(vias not_allowed)
				(pads allowed)
				(copperpour not_allowed)
				(footprints allowed)
			)
			(placement
				(enabled no)
				(sheetname "")
			)
			(fill
				(thermal_gap 0.5)
				(thermal_bridge_width 0.5)
				(island_removal_mode 0)
			)
			(polygon
				(pts
					(xy 169.7736 -131.6228) (xy 170.2816 -131.6228) (xy 170.2816 -131.2418) (xy 169.7736 -131.2418)
				)
			)
		)
		(zone
			(layer "F.Cu")
			(hatch none 0.5)
			(connect_pads
				(clearance 0)
			)
			(min_thickness 0.25)
			(keepout
				(tracks not_allowed)
				(vias allowed)
				(pads allowed)
				(copperpour not_allowed)
				(footprints allowed)
			)
			(placement
				(enabled no)
				(sheetname "")
			)
			(fill
				(thermal_gap 0.5)
				(thermal_bridge_width 0.5)
				(island_removal_mode 0)
			)
			(polygon
				(pts
					(xy 169.7736 -131.2418) (xy 170.2816 -131.2418) (xy 170.2816 -131.6228) (xy 169.7736 -131.6228)
				)
			)
		)
	)
)
